# S9S_MB_2U (Grand Teton) — schematic netlist excerpt (pin names and nets, part order shuffled) for the footprints in the layout excerpt that follows; sources: Cadence DE-HDL packaged netlist, KiCad conversion of 03242023_DA0F0TMBIJ0_F0T_Motherboard_J_brd_V01_OCP.brd

R2399  Q_RES  150 1% CHIP  pkg 0402LF  page 278 : A = SVID_CLK1_CPU0_R ; B = SVID_CLK_PVCCD_HV_CPU0_R
R3131  Q_RES  10K 1% CHIP  pkg 0402LF  page 236 : A = P3V3_AUX ; B = PCA9543_S3M_INT3_N

(kicad_pcb
	(version 20260206)
	(generator "pcbnew")
	(generator_version "10.0")
	(general
		(thickness 1.6)
		(legacy_teardrops no)
	)
	(paper "A4")
	(title_block
		(title "03242023_DA0F0TMBIJ0_F0T_Motherboard_J_brd_V01_OCP.brd")
		(comment 1 "Grand Teton / footprints 3288-3289 of 6105")
	)
	(layers
		(0 "F.Cu" signal "TOP")
		(4 "In1.Cu" signal "GND")
		(6 "In2.Cu" signal "IN1")
		(8 "In3.Cu" signal "GND1")
		(10 "In4.Cu" signal "IN2")
		(12 "In5.Cu" signal "GND2")
		(14 "In6.Cu" signal "IN3")
		(16 "In7.Cu" signal "GND3")
		(18 "In8.Cu" signal "VCC")
		(20 "In9.Cu" signal "VCC1")
		(22 "In10.Cu" signal "GND4")
		(24 "In11.Cu" signal "IN4")
		(26 "In12.Cu" signal "GND5")
		(28 "In13.Cu" signal "IN5")
		(30 "In14.Cu" signal "GND6")
		(32 "In15.Cu" signal "IN6")
		(34 "In16.Cu" signal "GND7")
		(2 "B.Cu" signal "BOTTOM")
		(9 "F.Adhes" user "F.Adhesive")
		(11 "B.Adhes" user "B.Adhesive")
		(13 "F.Paste" user "Package Geometry/Pastemask Top")
		(15 "B.Paste" user "Package Geometry/Pastemask Bottom")
		(5 "F.SilkS" user "Ref Des/Silkscreen Top")
		(7 "B.SilkS" user "Ref Des/Silkscreen Bottom")
		(1 "F.Mask" user "Board Geometry/Soldermask Top")
		(3 "B.Mask" user "Board Geometry/Soldermask Bottom")
		(17 "Dwgs.User" user "User.Drawings")
		(19 "Cmts.User" user "User.Comments")
		(21 "Eco1.User" user "User.Eco1")
		(23 "Eco2.User" user "User.Eco2")
		(25 "Edge.Cuts" user "Board Geometry/Outline")
		(27 "Margin" user)
		(31 "F.CrtYd" user "Package Geometry/Place Bound Top")
		(29 "B.CrtYd" user "Package Geometry/Place Bound Bottom")
		(35 "F.Fab" user "Ref Des/Assembly Top")
		(33 "B.Fab" user "Ref Des/Assembly Bottom")
	)
	(footprint ""
		(layer "F.Cu")
		(at 148.98243 -77.229208)
		(property "Reference" "R3131"
			(at 0 0 0)
			(layer "F.SilkS")
			(hide yes)
			(effects
				(font
					(size 1.27 1.27)
				)
			)
		)
		(property "Value" ""
			(at 0 0 0)
			(layer "F.Fab")
			(effects
				(font
					(size 1.27 1.27)
				)
			)
		)
		(duplicate_pad_numbers_are_jumpers no)
		(fp_line
			(start -0.7874 -0.4064)
			(end 0.7874 -0.4064)
			(stroke
				(width 0.1524)
				(type default)
			)
			(layer "F.SilkS")
		)
		(fp_line
			(start -0.7874 0.4064)
			(end -0.7874 -0.4064)
			(stroke
				(width 0.1524)
				(type default)
			)
			(layer "F.SilkS")
		)
		(fp_line
			(start 0.7874 -0.4064)
			(end 0.7874 0.4064)
			(stroke
				(width 0.1524)
				(type default)
			)
			(layer "F.SilkS")
		)
		(fp_line
			(start 0.7874 0.4064)
			(end -0.7874 0.4064)
			(stroke
				(width 0.1524)
				(type default)
			)
			(layer "F.SilkS")
		)
		(fp_line
			(start -0.67945 -0.305054)
			(end -0.12065 -0.305054)
			(stroke
				(width 0.1)
				(type default)
			)
			(layer "F.Fab")
		)
		(fp_line
			(start -0.67945 0.3048)
			(end -0.67945 -0.305054)
			(stroke
				(width 0.1)
				(type default)
			)
			(layer "F.Fab")
		)
		(fp_line
			(start -0.12065 -0.305054)
			(end -0.12065 -0.2794)
			(stroke
				(width 0.1)
				(type default)
			)
			(layer "F.Fab")
		)
		(fp_line
			(start -0.12065 -0.2794)
			(end 0.12065 -0.2794)
			(stroke
				(width 0.1)
				(type default)
			)
			(layer "F.Fab")
		)
		(fp_line
			(start -0.12065 0.2794)
			(end -0.12065 0.3048)
			(stroke
				(width 0.1)
				(type default)
			)
			(layer "F.Fab")
		)
		(fp_line
			(start -0.12065 0.3048)
			(end -0.67945 0.3048)
			(stroke
				(width 0.1)
				(type default)
			)
			(layer "F.Fab")
		)
		(fp_line
			(start 0.120396 0.2794)
			(end -0.12065 0.2794)
			(stroke
				(width 0.1)
				(type default)
			)
			(layer "F.Fab")
		)
		(fp_line
			(start 0.120396 0.3048)
			(end 0.120396 0.2794)
			(stroke
				(width 0.1)
				(type default)
			)
			(layer "F.Fab")
		)
		(fp_line
			(start 0.12065 -0.3048)
			(end 0.67945 -0.3048)
			(stroke
				(width 0.1)
				(type default)
			)
			(layer "F.Fab")
		)
		(fp_line
			(start 0.12065 -0.2794)
			(end 0.12065 -0.3048)
			(stroke
				(width 0.1)
				(type default)
			)
			(layer "F.Fab")
		)
		(fp_line
			(start 0.67945 -0.3048)
			(end 0.67945 0.3048)
			(stroke
				(width 0.1)
				(type default)
			)
			(layer "F.Fab")
		)
		(fp_line
			(start 0.67945 0.3048)
			(end 0.120396 0.3048)
			(stroke
				(width 0.1)
				(type default)
			)
			(layer "F.Fab")
		)
		(pad "1" smd circle
			(at -0.40005 0)
			(size 0 0)
			(layers "F.Cu" "F.Mask" "F.Paste")
			(net "P3V3_AUX")
		)
		(pad "2" smd circle
			(at 0.40005 0)
			(size 0 0)
			(layers "F.Cu" "F.Mask" "F.Paste")
			(net "PCA9543_S3M_INT3_N")
		)
	)
	(footprint ""
		(layer "F.Cu")
		(at 437.242966 -123.664726 180)
		(property "Reference" "R2399"
			(at 0 0 180)
			(layer "F.SilkS")
			(hide yes)
			(effects
				(font
					(size 1.27 1.27)
				)
			)
		)
		(property "Value" ""
			(at 0 0 180)
			(layer "F.Fab")
			(effects
				(font
					(size 1.27 1.27)
				)
			)
		)
		(duplicate_pad_numbers_are_jumpers no)
		(fp_line
			(start 0.7874 0.4064)
			(end -0.7874 0.4064)
			(stroke
				(width 0.1524)
				(type default)
			)
			(layer "F.SilkS")
		)
		(fp_line
			(start 0.7874 -0.4064)
			(end 0.7874 0.4064)
			(stroke
				(width 0.1524)
				(type default)
			)
			(layer "F.SilkS")
		)
		(fp_line
			(start -0.7874 0.4064)
			(end -0.7874 -0.4064)
			(stroke
				(width 0.1524)
				(type default)
			)
			(layer "F.SilkS")
		)
		(fp_line
			(start -0.7874 -0.4064)
			(end 0.7874 -0.4064)
			(stroke
				(width 0.1524)
				(type default)
			)
			(layer "F.SilkS")
		)
		(fp_line
			(start 0.67945 0.3048)
			(end 0.120396 0.3048)
			(stroke
				(width 0.1)
				(type default)
			)
			(layer "F.Fab")
		)
		(fp_line
			(start 0.67945 -0.3048)
			(end 0.67945 0.3048)
			(stroke
				(width 0.1)
				(type default)
			)
			(layer "F.Fab")
		)
		(fp_line
			(start 0.12065 -0.2794)
			(end 0.12065 -0.3048)
			(stroke
				(width 0.1)
				(type default)
			)
			(layer "F.Fab")
		)
		(fp_line
			(start 0.12065 -0.3048)
			(end 0.67945 -0.3048)
			(stroke
				(width 0.1)
				(type default)
			)
			(layer "F.Fab")
		)
		(fp_line
			(start 0.120396 0.3048)
			(end 0.120396 0.2794)
			(stroke
				(width 0.1)
				(type default)
			)
			(layer "F.Fab")
		)
		(fp_line
			(start 0.120396 0.2794)
			(end -0.12065 0.2794)
			(stroke
				(width 0.1)
				(type default)
			)
			(layer "F.Fab")
		)
		(fp_line
			(start -0.12065 0.3048)
			(end -0.67945 0.3048)
			(stroke
				(width 0.1)
				(type default)
			)
			(layer "F.Fab")
		)
		(fp_line
			(start -0.12065 0.2794)
			(end -0.12065 0.3048)
			(stroke
				(width 0.1)
				(type default)
			)
			(layer "F.Fab")
		)
		(fp_line
			(start -0.12065 -0.2794)
			(end 0.12065 -0.2794)
			(stroke
				(width 0.1)
				(type default)
			)
			(layer "F.Fab")
		)
		(fp_line
			(start -0.12065 -0.305054)
			(end -0.12065 -0.2794)
			(stroke
				(width 0.1)
				(type default)
			)
			(layer "F.Fab")
		)
		(fp_line
			(start -0.67945 0.3048)
			(end -0.67945 -0.305054)
			(stroke
				(width 0.1)
				(type default)
			)
			(layer "F.Fab")
		)
		(fp_line
			(start -0.67945 -0.305054)
			(end -0.12065 -0.305054)
			(stroke
				(width 0.1)
				(type default)
			)
			(layer "F.Fab")
		)
		(pad "1" smd circle
			(at -0.40005 0 180)
			(size 0 0)
			(layers "F.Cu" "F.Mask" "F.Paste")
			(net "SVID_CLK1_CPU0_R")
		)
		(pad "2" smd circle
			(at 0.40005 0 180)
			(size 0 0)
			(layers "F.Cu" "F.Mask" "F.Paste")
			(net "SVID_CLK_PVCCD_HV_CPU0_R")
		)
	)
)
